(kicad_pcb
	(version 20260206)
	(generator "pcbnew")
	(generator_version "10.0")
	(general
		(thickness 1.6)
		(legacy_teardrops no)
	)
	(paper "A4")
	(title_block
		(title "v1-chassis-manager — T6M_CM_d_v01_1031_1645.brd")
		(comment 1 "Open CloudServer (Microsoft) / footprints 543-549 of 2512")
	)
	(layers
		(0 "F.Cu" signal "TOP")
		(4 "In1.Cu" signal "GND1")
		(6 "In2.Cu" signal "IN1")
		(8 "In3.Cu" signal "VCC1")
		(10 "In4.Cu" signal "VCC2")
		(12 "In5.Cu" signal "GND2")
		(14 "In6.Cu" signal "IN2")
		(16 "In7.Cu" signal "IN3")
		(18 "In8.Cu" signal "GND3")
		(2 "B.Cu" signal "BOTTOM")
		(9 "F.Adhes" user "F.Adhesive")
		(11 "B.Adhes" user "B.Adhesive")
		(13 "F.Paste" user "Package Geometry/Pastemask Top")
		(15 "B.Paste" user "Package Geometry/Pastemask Bottom")
		(5 "F.SilkS" user "Ref Des/Silkscreen Top")
		(7 "B.SilkS" user "Ref Des/Silkscreen Bottom")
		(1 "F.Mask" user "Board Geometry/Soldermask Top")
		(3 "B.Mask" user "Board Geometry/Soldermask Bottom")
		(17 "Dwgs.User" user "User.Drawings")
		(19 "Cmts.User" user "User.Comments")
		(21 "Eco1.User" user "User.Eco1")
		(23 "Eco2.User" user "User.Eco2")
		(25 "Edge.Cuts" user "Board Geometry/Outline")
		(27 "Margin" user)
		(31 "F.CrtYd" user "Package Geometry/Place Bound Top")
		(29 "B.CrtYd" user "Package Geometry/Place Bound Bottom")
		(35 "F.Fab" user "Ref Des/Assembly Top")
		(33 "B.Fab" user "Ref Des/Assembly Bottom")
	)
	(footprint ""
		(layer "F.Cu")
		(at 106.426508 -178.984656)
		(property "Reference" "C573"
			(at -0.442468 -4.012692 0)
			(unlocked yes)
			(layer "F.SilkS")
			(effects
				(font
					(size 0.7874 0.5842)
					(thickness 0.1524)
				)
				(justify left)
			)
		)
		(property "Value" ""
			(at 0 0 0)
			(layer "F.Fab")
			(effects
				(font
					(size 1.27 1.27)
				)
			)
		)
		(duplicate_pad_numbers_are_jumpers no)
		(fp_line
			(start -0.7874 -0.4064)
			(end 0.7874 -0.4064)
			(stroke
				(width 0.1524)
				(type default)
			)
			(layer "F.SilkS")
		)
		(fp_line
			(start -0.7874 0.4064)
			(end -0.7874 -0.4064)
			(stroke
				(width 0.1524)
				(type default)
			)
			(layer "F.SilkS")
		)
		(fp_line
			(start 0 0.381)
			(end 0 -0.381)
			(stroke
				(width 0.1524)
				(type default)
			)
			(layer "F.SilkS")
		)
		(fp_line
			(start 0.7874 -0.4064)
			(end 0.7874 0.4064)
			(stroke
				(width 0.1524)
				(type default)
			)
			(layer "F.SilkS")
		)
		(fp_line
			(start 0.7874 0.4064)
			(end -0.7874 0.4064)
			(stroke
				(width 0.1524)
				(type default)
			)
			(layer "F.SilkS")
		)
		(fp_poly
			(pts
				(xy -0.5334 0.254) (xy -0.635 0.254) (xy -0.635 0.2286) (xy -0.635 -0.254) (xy -0.5334 -0.254) (xy -0.5334 -0.2794)
				(xy 0.5334 -0.2794) (xy 0.5334 -0.254) (xy 0.635 -0.254) (xy 0.635 0.254) (xy 0.5334 0.254) (xy 0.5334 0.2794)
				(xy -0.508 0.2794) (xy -0.5334 0.2794)
			)
			(stroke
				(width 0)
				(type default)
			)
			(fill no)
			(layer "F.CrtYd")
		)
		(pad "1" smd rect
			(at 0.40005 0)
			(size 0.4572 0.508)
			(layers "F.Cu" "F.Mask" "F.Paste")
			(net "GND")
		)
		(pad "2" smd rect
			(at -0.40005 0)
			(size 0.4572 0.508)
			(layers "F.Cu" "F.Mask" "F.Paste")
			(net "P3V3_NODE1")
		)
	)
	(footprint ""
		(layer "F.Cu")
		(at 78.522068 -94.131892 90)
		(property "Reference" "R156"
			(at -55.53329 24.090122 90)
			(unlocked yes)
			(layer "F.SilkS")
			(effects
				(font
					(size 0.7874 0.5842)
					(thickness 0.1524)
				)
				(justify left)
			)
		)
		(property "Value" ""
			(at 0 0 90)
			(layer "F.Fab")
			(effects
				(font
					(size 1.27 1.27)
				)
			)
		)
		(duplicate_pad_numbers_are_jumpers no)
		(fp_line
			(start 0.7874 -0.4064)
			(end 0.7874 0.4064)
			(stroke
				(width 0.1524)
				(type default)
			)
			(layer "F.SilkS")
		)
		(fp_line
			(start -0.7874 -0.4064)
			(end 0.7874 -0.4064)
			(stroke
				(width 0.1524)
				(type default)
			)
			(layer "F.SilkS")
		)
		(fp_line
			(start 0.7874 0.4064)
			(end -0.7874 0.4064)
			(stroke
				(width 0.1524)
				(type default)
			)
			(layer "F.SilkS")
		)
		(fp_line
			(start -0.7874 0.4064)
			(end -0.7874 -0.4064)
			(stroke
				(width 0.1524)
				(type default)
			)
			(layer "F.SilkS")
		)
		(fp_poly
			(pts
				(xy -0.508 0.2794) (xy -0.508 0.2286) (xy -0.635 0.2286) (xy -0.635 -0.254) (xy -0.5334 -0.254)
				(xy -0.5334 -0.2794) (xy 0.5334 -0.2794) (xy 0.5334 -0.254) (xy 0.635 -0.254) (xy 0.635 0.254) (xy 0.5334 0.254)
				(xy 0.5334 0.2794)
			)
			(stroke
				(width 0)
				(type default)
			)
			(fill no)
			(layer "F.CrtYd")
		)
		(pad "1" smd rect
			(at 0.40005 0 90)
			(size 0.4572 0.508)
			(layers "F.Cu" "F.Mask" "F.Paste")
			(net "GND")
		)
		(pad "2" smd rect
			(at -0.40005 0 90)
			(size 0.4572 0.508)
			(layers "F.Cu" "F.Mask" "F.Paste")
			(net "PU_CPU_NODE1_BRD_ID0")
		)
	)
	(footprint ""
		(layer "F.Cu")
		(at 116.007388 -135.617204 -90)
		(property "Reference" "PR66"
			(at -2.629916 -5.241798 90)
			(unlocked yes)
			(layer "F.SilkS")
			(effects
				(font
					(size 0.635 0.4064)
					(thickness 0.1524)
				)
				(justify left)
			)
		)
		(property "Value" ""
			(at 0 0 270)
			(layer "F.Fab")
			(effects
				(font
					(size 1.27 1.27)
				)
			)
		)
		(duplicate_pad_numbers_are_jumpers no)
		(fp_line
			(start -0.7874 0.4064)
			(end -0.7874 -0.4064)
			(stroke
				(width 0.1524)
				(type default)
			)
			(layer "F.SilkS")
		)
		(fp_line
			(start 0.7874 0.4064)
			(end -0.7874 0.4064)
			(stroke
				(width 0.1524)
				(type default)
			)
			(layer "F.SilkS")
		)
		(fp_line
			(start -0.7874 -0.4064)
			(end 0.7874 -0.4064)
			(stroke
				(width 0.1524)
				(type default)
			)
			(layer "F.SilkS")
		)
		(fp_line
			(start 0.7874 -0.4064)
			(end 0.7874 0.4064)
			(stroke
				(width 0.1524)
				(type default)
			)
			(layer "F.SilkS")
		)
		(fp_poly
			(pts
				(xy -0.508 0.2794) (xy -0.508 0.2286) (xy -0.635 0.2286) (xy -0.635 -0.254) (xy -0.5334 -0.254)
				(xy -0.5334 -0.2794) (xy 0.5334 -0.2794) (xy 0.5334 -0.254) (xy 0.635 -0.254) (xy 0.635 0.254) (xy 0.5334 0.254)
				(xy 0.5334 0.2794)
			)
			(stroke
				(width 0)
				(type default)
			)
			(fill no)
			(layer "F.CrtYd")
		)
		(pad "1" smd rect
			(at 0.40005 0 270)
			(size 0.4572 0.508)
			(layers "F.Cu" "F.Mask" "F.Paste")
			(net "VR_PVCCP_NODE1_COMP_RC")
		)
		(pad "2" smd rect
			(at -0.40005 0 270)
			(size 0.4572 0.508)
			(layers "F.Cu" "F.Mask" "F.Paste")
			(net "VR_PVCCP_NODE1_FB")
		)
	)
	(footprint ""
		(layer "F.Cu")
		(at 41.303448 -12.945872)
		(property "Reference" "PC76"
			(at 1.017524 -2.261108 90)
			(unlocked yes)
			(layer "F.SilkS")
			(effects
				(font
					(size 0.7874 0.5842)
					(thickness 0.1524)
				)
			)
		)
		(property "Value" ""
			(at 0 0 0)
			(layer "F.Fab")
			(effects
				(font
					(size 1.27 1.27)
				)
			)
		)
		(duplicate_pad_numbers_are_jumpers no)
		(fp_line
			(start -1.2954 -0.5842)
			(end 1.2954 -0.5842)
			(stroke
				(width 0.1524)
				(type default)
			)
			(layer "F.SilkS")
		)
		(fp_line
			(start -1.2954 0.5842)
			(end -1.2954 -0.5842)
			(stroke
				(width 0.1524)
				(type default)
			)
			(layer "F.SilkS")
		)
		(fp_line
			(start 0 -0.5842)
			(end 0 0.5842)
			(stroke
				(width 0.1524)
				(type default)
			)
			(layer "F.SilkS")
		)
		(fp_line
			(start 1.2954 -0.5842)
			(end 1.2954 0.5842)
			(stroke
				(width 0.1524)
				(type default)
			)
			(layer "F.SilkS")
		)
		(fp_line
			(start 1.2954 0.5842)
			(end -1.2954 0.5842)
			(stroke
				(width 0.1524)
				(type default)
			)
			(layer "F.SilkS")
		)
		(fp_poly
			(pts
				(xy 0.8636 -0.4572) (xy 0.8636 -0.3556) (xy 1.143 -0.3556) (xy 1.143 0.3556) (xy 0.8636 0.3556)
				(xy 0.8636 0.4572) (xy -0.8636 0.4572) (xy -0.8636 0.3556) (xy -1.143 0.3556) (xy -1.143 -0.3556)
				(xy -0.8636 -0.3556) (xy -0.8636 -0.4572)
			)
			(stroke
				(width 0)
				(type default)
			)
			(fill no)
			(layer "F.CrtYd")
		)
		(fp_line
			(start -0.884936 -0.504952)
			(end 0.884936 -0.504952)
			(stroke
				(width 0.1)
				(type default)
			)
			(layer "F.Fab")
		)
		(fp_line
			(start -0.884936 0.504952)
			(end -0.884936 -0.504952)
			(stroke
				(width 0.1)
				(type default)
			)
			(layer "F.Fab")
		)
		(fp_line
			(start 0.884936 -0.504952)
			(end 0.884936 0.504952)
			(stroke
				(width 0.1)
				(type default)
			)
			(layer "F.Fab")
		)
		(fp_line
			(start 0.884936 0.504952)
			(end -0.884936 0.504952)
			(stroke
				(width 0.1)
				(type default)
			)
			(layer "F.Fab")
		)
		(pad "1" smd rect
			(at 0.7366 0 90)
			(size 0.7112 0.8128)
			(layers "F.Cu" "F.Mask" "F.Paste")
			(net "GND")
		)
		(pad "2" smd rect
			(at -0.7366 0 90)
			(size 0.7112 0.8128)
			(layers "F.Cu" "F.Mask" "F.Paste")
			(net "P5V_STB_NODE1")
		)
	)
	(footprint ""
		(layer "F.Cu")
		(at 143.36776 -185.205624 90)
		(property "Reference" "C762"
			(at 4.768088 -0.544068 90)
			(unlocked yes)
			(layer "F.SilkS")
			(effects
				(font
					(size 0.7874 0.5842)
					(thickness 0.1524)
				)
				(justify left)
			)
		)
		(property "Value" ""
			(at 0 0 90)
			(layer "F.Fab")
			(effects
				(font
					(size 1.27 1.27)
				)
			)
		)
		(duplicate_pad_numbers_are_jumpers no)
		(fp_line
			(start 0.7874 -0.4064)
			(end 0.7874 0.4064)
			(stroke
				(width 0.1524)
				(type default)
			)
			(layer "F.SilkS")
		)
		(fp_line
			(start -0.7874 -0.4064)
			(end 0.7874 -0.4064)
			(stroke
				(width 0.1524)
				(type default)
			)
			(layer "F.SilkS")
		)
		(fp_line
			(start 0 0.381)
			(end 0 -0.381)
			(stroke
				(width 0.1524)
				(type default)
			)
			(layer "F.SilkS")
		)
		(fp_line
			(start 0.7874 0.4064)
			(end -0.7874 0.4064)
			(stroke
				(width 0.1524)
				(type default)
			)
			(layer "F.SilkS")
		)
		(fp_line
			(start -0.7874 0.4064)
			(end -0.7874 -0.4064)
			(stroke
				(width 0.1524)
				(type default)
			)
			(layer "F.SilkS")
		)
		(fp_poly
			(pts
				(xy -0.5334 0.254) (xy -0.635 0.254) (xy -0.635 0.2286) (xy -0.635 -0.254) (xy -0.5334 -0.254) (xy -0.5334 -0.2794)
				(xy 0.5334 -0.2794) (xy 0.5334 -0.254) (xy 0.635 -0.254) (xy 0.635 0.254) (xy 0.5334 0.254) (xy 0.5334 0.2794)
				(xy -0.508 0.2794) (xy -0.5334 0.2794)
			)
			(stroke
				(width 0)
				(type default)
			)
			(fill no)
			(layer "F.CrtYd")
		)
		(pad "1" smd rect
			(at 0.40005 0 90)
			(size 0.4572 0.508)
			(layers "F.Cu" "F.Mask" "F.Paste")
			(net "UART_T12_NODE4_RXD")
		)
		(pad "2" smd rect
			(at -0.40005 0 90)
			(size 0.4572 0.508)
			(layers "F.Cu" "F.Mask" "F.Paste")
			(net "GND")
		)
	)
	(footprint ""
		(layer "F.Cu")
		(at 109.45876 -185.205624 -90)
		(property "Reference" "R890"
			(at -4.768088 -0.724408 90)
			(unlocked yes)
			(layer "F.SilkS")
			(effects
				(font
					(size 0.7874 0.5842)
					(thickness 0.1524)
				)
				(justify left)
			)
		)
		(property "Value" ""
			(at 0 0 270)
			(layer "F.Fab")
			(effects
				(font
					(size 1.27 1.27)
				)
			)
		)
		(duplicate_pad_numbers_are_jumpers no)
		(fp_line
			(start -0.7874 0.4064)
			(end -0.7874 -0.4064)
			(stroke
				(width 0.1524)
				(type default)
			)
			(layer "F.SilkS")
		)
		(fp_line
			(start 0.7874 0.4064)
			(end -0.7874 0.4064)
			(stroke
				(width 0.1524)
				(type default)
			)
			(layer "F.SilkS")
		)
		(fp_line
			(start -0.7874 -0.4064)
			(end 0.7874 -0.4064)
			(stroke
				(width 0.1524)
				(type default)
			)
			(layer "F.SilkS")
		)
		(fp_line
			(start 0.7874 -0.4064)
			(end 0.7874 0.4064)
			(stroke
				(width 0.1524)
				(type default)
			)
			(layer "F.SilkS")
		)
		(fp_poly
			(pts
				(xy -0.508 0.2794) (xy -0.508 0.2286) (xy -0.635 0.2286) (xy -0.635 -0.254) (xy -0.5334 -0.254)
				(xy -0.5334 -0.2794) (xy 0.5334 -0.2794) (xy 0.5334 -0.254) (xy 0.635 -0.254) (xy 0.635 0.254) (xy 0.5334 0.254)
				(xy 0.5334 0.2794)
			)
			(stroke
				(width 0)
				(type default)
			)
			(fill no)
			(layer "F.CrtYd")
		)
		(pad "1" smd rect
			(at 0.40005 0 270)
			(size 0.4572 0.508)
			(layers "F.Cu" "F.Mask" "F.Paste")
			(net "T6_NODE3_EN")
		)
		(pad "2" smd rect
			(at -0.40005 0 270)
			(size 0.4572 0.508)
			(layers "F.Cu" "F.Mask" "F.Paste")
			(net "T6_NODE3_EN_R")
		)
	)
	(footprint ""
		(layer "F.Cu")
		(at 161.762694 -131.24942)
		(property "Reference" "R1032"
			(at -1.957578 -1.021334 0)
			(unlocked yes)
			(layer "F.SilkS")
			(effects
				(font
					(size 0.7874 0.5842)
					(thickness 0.1524)
				)
				(justify left)
			)
		)
		(property "Value" ""
			(at 0 0 0)
			(layer "F.Fab")
			(effects
				(font
					(size 1.27 1.27)
				)
			)
		)
		(duplicate_pad_numbers_are_jumpers no)
		(fp_line
			(start -0.7874 -0.4064)
			(end 0.7874 -0.4064)
			(stroke
				(width 0.1524)
				(type default)
			)
			(layer "F.SilkS")
		)
		(fp_line
			(start -0.7874 0.4064)
			(end -0.7874 -0.4064)
			(stroke
				(width 0.1524)
				(type default)
			)
			(layer "F.SilkS")
		)
		(fp_line
			(start 0.7874 -0.4064)
			(end 0.7874 0.4064)
			(stroke
				(width 0.1524)
				(type default)
			)
			(layer "F.SilkS")
		)
		(fp_line
			(start 0.7874 0.4064)
			(end -0.7874 0.4064)
			(stroke
				(width 0.1524)
				(type default)
			)
			(layer "F.SilkS")
		)
		(fp_poly
			(pts
				(xy -0.508 0.2794) (xy -0.508 0.2286) (xy -0.635 0.2286) (xy -0.635 -0.254) (xy -0.5334 -0.254)
				(xy -0.5334 -0.2794) (xy 0.5334 -0.2794) (xy 0.5334 -0.254) (xy 0.635 -0.254) (xy 0.635 0.254) (xy 0.5334 0.254)
				(xy 0.5334 0.2794)
			)
			(stroke
				(width 0)
				(type default)
			)
			(fill no)
			(layer "F.CrtYd")
		)
		(pad "1" smd rect
			(at 0.40005 0)
			(size 0.4572 0.508)
			(layers "F.Cu" "F.Mask" "F.Paste")
			(net "P3V3_STB_NODE1")
		)
		(pad "2" smd rect
			(at -0.40005 0)
			(size 0.4572 0.508)
			(layers "F.Cu" "F.Mask" "F.Paste")
			(net "LED_CPU_NODE1_CPLD_D")
		)
	)
)
